# S9S_MB_2U (Grand Teton) — schematic netlist excerpt (pin names and nets, part order shuffled) for the footprints in the layout excerpt that follows; sources: Cadence DE-HDL packaged netlist, KiCad conversion of 03242023_DA0F0TMBIJ0_F0T_Motherboard_J_brd_V01_OCP.brd

PC2165  Q_CAP  1UF 25V 10% X6S  pkg C0402  page 163 : A = P12V_AUX ; B = GND
PL110  Q_INDUCTOR  100NH/16A IND  pkg SMLF  page 262 : \1\ = P12V_AUX ; \2\ = SW_P12V_AUX_P1V05_PCH_AUX_FLT
C1974  Q_CAP  1000PF 50V 5% EMPTY  pkg 0402  page 147 : A = GPU_FPGA_THERM_OVERT_ISO_N ; B = GND

(kicad_pcb
	(version 20260206)
	(generator "pcbnew")
	(generator_version "10.0")
	(general
		(thickness 1.6)
		(legacy_teardrops no)
	)
	(paper "A4")
	(title_block
		(title "03242023_DA0F0TMBIJ0_F0T_Motherboard_J_brd_V01_OCP.brd")
		(comment 1 "Grand Teton / footprints 3717-3719 of 6105")
	)
	(layers
		(0 "F.Cu" signal "TOP")
		(4 "In1.Cu" signal "GND")
		(6 "In2.Cu" signal "IN1")
		(8 "In3.Cu" signal "GND1")
		(10 "In4.Cu" signal "IN2")
		(12 "In5.Cu" signal "GND2")
		(14 "In6.Cu" signal "IN3")
		(16 "In7.Cu" signal "GND3")
		(18 "In8.Cu" signal "VCC")
		(20 "In9.Cu" signal "VCC1")
		(22 "In10.Cu" signal "GND4")
		(24 "In11.Cu" signal "IN4")
		(26 "In12.Cu" signal "GND5")
		(28 "In13.Cu" signal "IN5")
		(30 "In14.Cu" signal "GND6")
		(32 "In15.Cu" signal "IN6")
		(34 "In16.Cu" signal "GND7")
		(2 "B.Cu" signal "BOTTOM")
		(9 "F.Adhes" user "F.Adhesive")
		(11 "B.Adhes" user "B.Adhesive")
		(13 "F.Paste" user "Package Geometry/Pastemask Top")
		(15 "B.Paste" user "Package Geometry/Pastemask Bottom")
		(5 "F.SilkS" user "Ref Des/Silkscreen Top")
		(7 "B.SilkS" user "Ref Des/Silkscreen Bottom")
		(1 "F.Mask" user "Board Geometry/Soldermask Top")
		(3 "B.Mask" user "Board Geometry/Soldermask Bottom")
		(17 "Dwgs.User" user "User.Drawings")
		(19 "Cmts.User" user "User.Comments")
		(21 "Eco1.User" user "User.Eco1")
		(23 "Eco2.User" user "User.Eco2")
		(25 "Edge.Cuts" user "Board Geometry/Outline")
		(27 "Margin" user)
		(31 "F.CrtYd" user "Package Geometry/Place Bound Top")
		(29 "B.CrtYd" user "Package Geometry/Place Bound Bottom")
		(35 "F.Fab" user "Ref Des/Assembly Top")
		(33 "B.Fab" user "Ref Des/Assembly Bottom")
	)
	(footprint ""
		(layer "F.Cu")
		(at 73.496678 -29.845762 90)
		(property "Reference" "PC2165"
			(at 0 0 90)
			(layer "F.SilkS")
			(hide yes)
			(effects
				(font
					(size 1.27 1.27)
				)
			)
		)
		(property "Value" ""
			(at 0 0 90)
			(layer "F.Fab")
			(effects
				(font
					(size 1.27 1.27)
				)
			)
		)
		(duplicate_pad_numbers_are_jumpers no)
		(fp_line
			(start 0.7874 -0.4064)
			(end 0.7874 0.4064)
			(stroke
				(width 0.1524)
				(type default)
			)
			(layer "F.SilkS")
		)
		(fp_line
			(start -0.7874 -0.4064)
			(end 0.7874 -0.4064)
			(stroke
				(width 0.1524)
				(type default)
			)
			(layer "F.SilkS")
		)
		(fp_line
			(start 0.7874 0.4064)
			(end -0.7874 0.4064)
			(stroke
				(width 0.1524)
				(type default)
			)
			(layer "F.SilkS")
		)
		(fp_line
			(start -0.7874 0.4064)
			(end -0.7874 -0.4064)
			(stroke
				(width 0.1524)
				(type default)
			)
			(layer "F.SilkS")
		)
		(fp_line
			(start -0.12065 -0.305054)
			(end -0.12065 -0.2794)
			(stroke
				(width 0.1)
				(type default)
			)
			(layer "F.Fab")
		)
		(fp_line
			(start -0.67945 -0.305054)
			(end -0.12065 -0.305054)
			(stroke
				(width 0.1)
				(type default)
			)
			(layer "F.Fab")
		)
		(fp_line
			(start 0.67945 -0.3048)
			(end 0.67945 0.3048)
			(stroke
				(width 0.1)
				(type default)
			)
			(layer "F.Fab")
		)
		(fp_line
			(start 0.12065 -0.3048)
			(end 0.67945 -0.3048)
			(stroke
				(width 0.1)
				(type default)
			)
			(layer "F.Fab")
		)
		(fp_line
			(start 0.12065 -0.2794)
			(end 0.12065 -0.3048)
			(stroke
				(width 0.1)
				(type default)
			)
			(layer "F.Fab")
		)
		(fp_line
			(start -0.12065 -0.2794)
			(end 0.12065 -0.2794)
			(stroke
				(width 0.1)
				(type default)
			)
			(layer "F.Fab")
		)
		(fp_line
			(start 0.120396 0.2794)
			(end -0.12065 0.2794)
			(stroke
				(width 0.1)
				(type default)
			)
			(layer "F.Fab")
		)
		(fp_line
			(start -0.12065 0.2794)
			(end -0.12065 0.3048)
			(stroke
				(width 0.1)
				(type default)
			)
			(layer "F.Fab")
		)
		(fp_line
			(start 0.67945 0.3048)
			(end 0.120396 0.3048)
			(stroke
				(width 0.1)
				(type default)
			)
			(layer "F.Fab")
		)
		(fp_line
			(start 0.120396 0.3048)
			(end 0.120396 0.2794)
			(stroke
				(width 0.1)
				(type default)
			)
			(layer "F.Fab")
		)
		(fp_line
			(start -0.12065 0.3048)
			(end -0.67945 0.3048)
			(stroke
				(width 0.1)
				(type default)
			)
			(layer "F.Fab")
		)
		(fp_line
			(start -0.67945 0.3048)
			(end -0.67945 -0.305054)
			(stroke
				(width 0.1)
				(type default)
			)
			(layer "F.Fab")
		)
		(pad "1" smd circle
			(at -0.40005 0 90)
			(size 0 0)
			(layers "F.Cu" "F.Mask" "F.Paste")
			(net "P12V_AUX")
		)
		(pad "2" smd circle
			(at 0.40005 0 90)
			(size 0 0)
			(layers "F.Cu" "F.Mask" "F.Paste")
			(net "GND")
		)
	)
	(footprint ""
		(layer "F.Cu")
		(at 249.81535 -73.290684)
		(property "Reference" "PL110"
			(at -2.3876 -2.969768 0)
			(unlocked yes)
			(layer "F.SilkS")
			(effects
				(font
					(size 0.7874 0.5842)
					(thickness 0.1524)
				)
				(justify left)
			)
		)
		(property "Value" ""
			(at 0 0 0)
			(layer "F.Fab")
			(effects
				(font
					(size 1.27 1.27)
				)
			)
		)
		(duplicate_pad_numbers_are_jumpers no)
		(fp_line
			(start -2.249932 -2.249932)
			(end 2.249932 -2.249932)
			(stroke
				(width 0.1524)
				(type default)
			)
			(layer "F.SilkS")
		)
		(fp_line
			(start -2.249932 -1.3843)
			(end -2.249932 -2.249932)
			(stroke
				(width 0.1524)
				(type default)
			)
			(layer "F.SilkS")
		)
		(fp_line
			(start -2.249932 2.249932)
			(end -2.249932 1.3843)
			(stroke
				(width 0.1524)
				(type default)
			)
			(layer "F.SilkS")
		)
		(fp_line
			(start 2.249932 -2.249932)
			(end 2.249932 -1.3843)
			(stroke
				(width 0.1524)
				(type default)
			)
			(layer "F.SilkS")
		)
		(fp_line
			(start 2.249932 1.3843)
			(end 2.249932 2.249932)
			(stroke
				(width 0.1524)
				(type default)
			)
			(layer "F.SilkS")
		)
		(fp_line
			(start 2.249932 2.249932)
			(end -2.249932 2.249932)
			(stroke
				(width 0.1524)
				(type default)
			)
			(layer "F.SilkS")
		)
		(fp_line
			(start -2.249932 -2.249932)
			(end 2.249932 -2.249932)
			(stroke
				(width 0.1)
				(type default)
			)
			(layer "F.Fab")
		)
		(fp_line
			(start -2.249932 2.249932)
			(end -2.249932 -2.249932)
			(stroke
				(width 0.1)
				(type default)
			)
			(layer "F.Fab")
		)
		(fp_line
			(start 2.249932 -2.249932)
			(end 2.249932 2.249932)
			(stroke
				(width 0.1)
				(type default)
			)
			(layer "F.Fab")
		)
		(fp_line
			(start 2.249932 2.249932)
			(end -2.249932 2.249932)
			(stroke
				(width 0.1)
				(type default)
			)
			(layer "F.Fab")
		)
		(pad "1" smd rect
			(at -1.82499 0)
			(size 1.0668 2.5146)
			(layers "F.Cu" "F.Mask" "F.Paste")
			(net "P12V_AUX")
		)
		(pad "2" smd rect
			(at 1.82499 0)
			(size 1.0668 2.5146)
			(layers "F.Cu" "F.Mask" "F.Paste")
			(net "SW_P12V_AUX_P1V05_PCH_AUX_FLT")
		)
	)
	(footprint ""
		(layer "F.Cu")
		(at 24.050752 -404.842218 180)
		(property "Reference" "C1974"
			(at 0 0 180)
			(layer "F.SilkS")
			(hide yes)
			(effects
				(font
					(size 1.27 1.27)
				)
			)
		)
		(property "Value" ""
			(at 0 0 180)
			(layer "F.Fab")
			(effects
				(font
					(size 1.27 1.27)
				)
			)
		)
		(duplicate_pad_numbers_are_jumpers no)
		(fp_line
			(start 0.7874 0.4064)
			(end -0.7874 0.4064)
			(stroke
				(width 0.1524)
				(type default)
			)
			(layer "F.SilkS")
		)
		(fp_line
			(start 0.7874 -0.4064)
			(end 0.7874 0.4064)
			(stroke
				(width 0.1524)
				(type default)
			)
			(layer "F.SilkS")
		)
		(fp_line
			(start -0.7874 0.4064)
			(end -0.7874 -0.4064)
			(stroke
				(width 0.1524)
				(type default)
			)
			(layer "F.SilkS")
		)
		(fp_line
			(start -0.7874 -0.4064)
			(end 0.7874 -0.4064)
			(stroke
				(width 0.1524)
				(type default)
			)
			(layer "F.SilkS")
		)
		(fp_line
			(start 0.67945 0.3048)
			(end 0.120396 0.3048)
			(stroke
				(width 0.1)
				(type default)
			)
			(layer "F.Fab")
		)
		(fp_line
			(start 0.67945 -0.3048)
			(end 0.67945 0.3048)
			(stroke
				(width 0.1)
				(type default)
			)
			(layer "F.Fab")
		)
		(fp_line
			(start 0.12065 -0.2794)
			(end 0.12065 -0.3048)
			(stroke
				(width 0.1)
				(type default)
			)
			(layer "F.Fab")
		)
		(fp_line
			(start 0.12065 -0.3048)
			(end 0.67945 -0.3048)
			(stroke
				(width 0.1)
				(type default)
			)
			(layer "F.Fab")
		)
		(fp_line
			(start 0.120396 0.3048)
			(end 0.120396 0.2794)
			(stroke
				(width 0.1)
				(type default)
			)
			(layer "F.Fab")
		)
		(fp_line
			(start 0.120396 0.2794)
			(end -0.12065 0.2794)
			(stroke
				(width 0.1)
				(type default)
			)
			(layer "F.Fab")
		)
		(fp_line
			(start -0.12065 0.3048)
			(end -0.67945 0.3048)
			(stroke
				(width 0.1)
				(type default)
			)
			(layer "F.Fab")
		)
		(fp_line
			(start -0.12065 0.2794)
			(end -0.12065 0.3048)
			(stroke
				(width 0.1)
				(type default)
			)
			(layer "F.Fab")
		)
		(fp_line
			(start -0.12065 -0.2794)
			(end 0.12065 -0.2794)
			(stroke
				(width 0.1)
				(type default)
			)
			(layer "F.Fab")
		)
		(fp_line
			(start -0.12065 -0.305054)
			(end -0.12065 -0.2794)
			(stroke
				(width 0.1)
				(type default)
			)
			(layer "F.Fab")
		)
		(fp_line
			(start -0.67945 0.3048)
			(end -0.67945 -0.305054)
			(stroke
				(width 0.1)
				(type default)
			)
			(layer "F.Fab")
		)
		(fp_line
			(start -0.67945 -0.305054)
			(end -0.12065 -0.305054)
			(stroke
				(width 0.1)
				(type default)
			)
			(layer "F.Fab")
		)
		(pad "1" smd circle
			(at -0.40005 0 180)
			(size 0 0)
			(layers "F.Cu" "F.Mask" "F.Paste")
			(net "GPU_FPGA_THERM_OVERT_ISO_N")
		)
		(pad "2" smd circle
			(at 0.40005 0 180)
			(size 0 0)
			(layers "F.Cu" "F.Mask" "F.Paste")
			(net "GND")
		)
	)
)
